(kicad_pcb
	(version 20260206)
	(generator "pcbnew")
	(generator_version "10.0")
	(general
		(thickness 1.6)
		(legacy_teardrops no)
	)
	(paper "A4")
	(title_block
		(title "03242023_DA0F0TMBIJ0_F0T_Motherboard_J_brd_V01_OCP.brd")
		(comment 1 "Grand Teton / footprints 1188-1193 of 6105")
	)
	(layers
		(0 "F.Cu" signal "TOP")
		(4 "In1.Cu" signal "GND")
		(6 "In2.Cu" signal "IN1")
		(8 "In3.Cu" signal "GND1")
		(10 "In4.Cu" signal "IN2")
		(12 "In5.Cu" signal "GND2")
		(14 "In6.Cu" signal "IN3")
		(16 "In7.Cu" signal "GND3")
		(18 "In8.Cu" signal "VCC")
		(20 "In9.Cu" signal "VCC1")
		(22 "In10.Cu" signal "GND4")
		(24 "In11.Cu" signal "IN4")
		(26 "In12.Cu" signal "GND5")
		(28 "In13.Cu" signal "IN5")
		(30 "In14.Cu" signal "GND6")
		(32 "In15.Cu" signal "IN6")
		(34 "In16.Cu" signal "GND7")
		(2 "B.Cu" signal "BOTTOM")
		(9 "F.Adhes" user "F.Adhesive")
		(11 "B.Adhes" user "B.Adhesive")
		(13 "F.Paste" user "Package Geometry/Pastemask Top")
		(15 "B.Paste" user "Package Geometry/Pastemask Bottom")
		(5 "F.SilkS" user "Ref Des/Silkscreen Top")
		(7 "B.SilkS" user "Ref Des/Silkscreen Bottom")
		(1 "F.Mask" user "Board Geometry/Soldermask Top")
		(3 "B.Mask" user "Board Geometry/Soldermask Bottom")
		(17 "Dwgs.User" user "User.Drawings")
		(19 "Cmts.User" user "User.Comments")
		(21 "Eco1.User" user "User.Eco1")
		(23 "Eco2.User" user "User.Eco2")
		(25 "Edge.Cuts" user "Board Geometry/Outline")
		(27 "Margin" user)
		(31 "F.CrtYd" user "Package Geometry/Place Bound Top")
		(29 "B.CrtYd" user "Package Geometry/Place Bound Bottom")
		(35 "F.Fab" user "Ref Des/Assembly Top")
		(33 "B.Fab" user "Ref Des/Assembly Bottom")
	)
	(footprint ""
		(layer "F.Cu")
		(at 169.441622 -420.511478)
		(property "Reference" "R3429"
			(at 0 0 0)
			(layer "F.SilkS")
			(hide yes)
			(effects
				(font
					(size 1.27 1.27)
				)
			)
		)
		(property "Value" ""
			(at 0 0 0)
			(layer "F.Fab")
			(effects
				(font
					(size 1.27 1.27)
				)
			)
		)
		(duplicate_pad_numbers_are_jumpers no)
		(fp_line
			(start -0.7874 -0.4064)
			(end 0.7874 -0.4064)
			(stroke
				(width 0.1524)
				(type default)
			)
			(layer "F.SilkS")
		)
		(fp_line
			(start -0.7874 0.4064)
			(end -0.7874 -0.4064)
			(stroke
				(width 0.1524)
				(type default)
			)
			(layer "F.SilkS")
		)
		(fp_line
			(start 0.7874 -0.4064)
			(end 0.7874 0.4064)
			(stroke
				(width 0.1524)
				(type default)
			)
			(layer "F.SilkS")
		)
		(fp_line
			(start 0.7874 0.4064)
			(end -0.7874 0.4064)
			(stroke
				(width 0.1524)
				(type default)
			)
			(layer "F.SilkS")
		)
		(fp_line
			(start -0.67945 -0.305054)
			(end -0.12065 -0.305054)
			(stroke
				(width 0.1)
				(type default)
			)
			(layer "F.Fab")
		)
		(fp_line
			(start -0.67945 0.3048)
			(end -0.67945 -0.305054)
			(stroke
				(width 0.1)
				(type default)
			)
			(layer "F.Fab")
		)
		(fp_line
			(start -0.12065 -0.305054)
			(end -0.12065 -0.2794)
			(stroke
				(width 0.1)
				(type default)
			)
			(layer "F.Fab")
		)
		(fp_line
			(start -0.12065 -0.2794)
			(end 0.12065 -0.2794)
			(stroke
				(width 0.1)
				(type default)
			)
			(layer "F.Fab")
		)
		(fp_line
			(start -0.12065 0.2794)
			(end -0.12065 0.3048)
			(stroke
				(width 0.1)
				(type default)
			)
			(layer "F.Fab")
		)
		(fp_line
			(start -0.12065 0.3048)
			(end -0.67945 0.3048)
			(stroke
				(width 0.1)
				(type default)
			)
			(layer "F.Fab")
		)
		(fp_line
			(start 0.120396 0.2794)
			(end -0.12065 0.2794)
			(stroke
				(width 0.1)
				(type default)
			)
			(layer "F.Fab")
		)
		(fp_line
			(start 0.120396 0.3048)
			(end 0.120396 0.2794)
			(stroke
				(width 0.1)
				(type default)
			)
			(layer "F.Fab")
		)
		(fp_line
			(start 0.12065 -0.3048)
			(end 0.67945 -0.3048)
			(stroke
				(width 0.1)
				(type default)
			)
			(layer "F.Fab")
		)
		(fp_line
			(start 0.12065 -0.2794)
			(end 0.12065 -0.3048)
			(stroke
				(width 0.1)
				(type default)
			)
			(layer "F.Fab")
		)
		(fp_line
			(start 0.67945 -0.3048)
			(end 0.67945 0.3048)
			(stroke
				(width 0.1)
				(type default)
			)
			(layer "F.Fab")
		)
		(fp_line
			(start 0.67945 0.3048)
			(end 0.120396 0.3048)
			(stroke
				(width 0.1)
				(type default)
			)
			(layer "F.Fab")
		)
		(pad "1" smd circle
			(at -0.40005 0)
			(size 0 0)
			(layers "F.Cu" "F.Mask" "F.Paste")
			(net "P3V3_AUX")
		)
		(pad "2" smd circle
			(at 0.40005 0)
			(size 0 0)
			(layers "F.Cu" "F.Mask" "F.Paste")
			(net "GPU_BASE_HMC_READY")
		)
	)
	(footprint ""
		(layer "F.Cu")
		(at 111.332772 -133.663182)
		(property "Reference" "R3583"
			(at 0 0 0)
			(layer "F.SilkS")
			(hide yes)
			(effects
				(font
					(size 1.27 1.27)
				)
			)
		)
		(property "Value" ""
			(at 0 0 0)
			(layer "F.Fab")
			(effects
				(font
					(size 1.27 1.27)
				)
			)
		)
		(duplicate_pad_numbers_are_jumpers no)
		(fp_line
			(start -0.7874 -0.4064)
			(end 0.7874 -0.4064)
			(stroke
				(width 0.1524)
				(type default)
			)
			(layer "F.SilkS")
		)
		(fp_line
			(start -0.7874 0.4064)
			(end -0.7874 -0.4064)
			(stroke
				(width 0.1524)
				(type default)
			)
			(layer "F.SilkS")
		)
		(fp_line
			(start 0.7874 -0.4064)
			(end 0.7874 0.4064)
			(stroke
				(width 0.1524)
				(type default)
			)
			(layer "F.SilkS")
		)
		(fp_line
			(start 0.7874 0.4064)
			(end -0.7874 0.4064)
			(stroke
				(width 0.1524)
				(type default)
			)
			(layer "F.SilkS")
		)
		(fp_line
			(start -0.67945 -0.305054)
			(end -0.12065 -0.305054)
			(stroke
				(width 0.1)
				(type default)
			)
			(layer "F.Fab")
		)
		(fp_line
			(start -0.67945 0.3048)
			(end -0.67945 -0.305054)
			(stroke
				(width 0.1)
				(type default)
			)
			(layer "F.Fab")
		)
		(fp_line
			(start -0.12065 -0.305054)
			(end -0.12065 -0.2794)
			(stroke
				(width 0.1)
				(type default)
			)
			(layer "F.Fab")
		)
		(fp_line
			(start -0.12065 -0.2794)
			(end 0.12065 -0.2794)
			(stroke
				(width 0.1)
				(type default)
			)
			(layer "F.Fab")
		)
		(fp_line
			(start -0.12065 0.2794)
			(end -0.12065 0.3048)
			(stroke
				(width 0.1)
				(type default)
			)
			(layer "F.Fab")
		)
		(fp_line
			(start -0.12065 0.3048)
			(end -0.67945 0.3048)
			(stroke
				(width 0.1)
				(type default)
			)
			(layer "F.Fab")
		)
		(fp_line
			(start 0.120396 0.2794)
			(end -0.12065 0.2794)
			(stroke
				(width 0.1)
				(type default)
			)
			(layer "F.Fab")
		)
		(fp_line
			(start 0.120396 0.3048)
			(end 0.120396 0.2794)
			(stroke
				(width 0.1)
				(type default)
			)
			(layer "F.Fab")
		)
		(fp_line
			(start 0.12065 -0.3048)
			(end 0.67945 -0.3048)
			(stroke
				(width 0.1)
				(type default)
			)
			(layer "F.Fab")
		)
		(fp_line
			(start 0.12065 -0.2794)
			(end 0.12065 -0.3048)
			(stroke
				(width 0.1)
				(type default)
			)
			(layer "F.Fab")
		)
		(fp_line
			(start 0.67945 -0.3048)
			(end 0.67945 0.3048)
			(stroke
				(width 0.1)
				(type default)
			)
			(layer "F.Fab")
		)
		(fp_line
			(start 0.67945 0.3048)
			(end 0.120396 0.3048)
			(stroke
				(width 0.1)
				(type default)
			)
			(layer "F.Fab")
		)
		(pad "1" smd circle
			(at -0.40005 0)
			(size 0 0)
			(layers "F.Cu" "F.Mask" "F.Paste")
			(net "P3V3_AUX")
		)
		(pad "2" smd circle
			(at 0.40005 0)
			(size 0 0)
			(layers "F.Cu" "F.Mask" "F.Paste")
			(net "SMB_IOEXP_3V3AUX_SDA")
		)
	)
	(footprint ""
		(layer "F.Cu")
		(at 148.197824 -49.372012 180)
		(property "Reference" "R3560"
			(at 0 0 180)
			(layer "F.SilkS")
			(hide yes)
			(effects
				(font
					(size 1.27 1.27)
				)
			)
		)
		(property "Value" ""
			(at 0 0 180)
			(layer "F.Fab")
			(effects
				(font
					(size 1.27 1.27)
				)
			)
		)
		(duplicate_pad_numbers_are_jumpers no)
		(fp_line
			(start 0.7874 0.4064)
			(end -0.7874 0.4064)
			(stroke
				(width 0.1524)
				(type default)
			)
			(layer "F.SilkS")
		)
		(fp_line
			(start 0.7874 -0.4064)
			(end 0.7874 0.4064)
			(stroke
				(width 0.1524)
				(type default)
			)
			(layer "F.SilkS")
		)
		(fp_line
			(start -0.7874 0.4064)
			(end -0.7874 -0.4064)
			(stroke
				(width 0.1524)
				(type default)
			)
			(layer "F.SilkS")
		)
		(fp_line
			(start -0.7874 -0.4064)
			(end 0.7874 -0.4064)
			(stroke
				(width 0.1524)
				(type default)
			)
			(layer "F.SilkS")
		)
		(fp_line
			(start 0.67945 0.3048)
			(end 0.120396 0.3048)
			(stroke
				(width 0.1)
				(type default)
			)
			(layer "F.Fab")
		)
		(fp_line
			(start 0.67945 -0.3048)
			(end 0.67945 0.3048)
			(stroke
				(width 0.1)
				(type default)
			)
			(layer "F.Fab")
		)
		(fp_line
			(start 0.12065 -0.2794)
			(end 0.12065 -0.3048)
			(stroke
				(width 0.1)
				(type default)
			)
			(layer "F.Fab")
		)
		(fp_line
			(start 0.12065 -0.3048)
			(end 0.67945 -0.3048)
			(stroke
				(width 0.1)
				(type default)
			)
			(layer "F.Fab")
		)
		(fp_line
			(start 0.120396 0.3048)
			(end 0.120396 0.2794)
			(stroke
				(width 0.1)
				(type default)
			)
			(layer "F.Fab")
		)
		(fp_line
			(start 0.120396 0.2794)
			(end -0.12065 0.2794)
			(stroke
				(width 0.1)
				(type default)
			)
			(layer "F.Fab")
		)
		(fp_line
			(start -0.12065 0.3048)
			(end -0.67945 0.3048)
			(stroke
				(width 0.1)
				(type default)
			)
			(layer "F.Fab")
		)
		(fp_line
			(start -0.12065 0.2794)
			(end -0.12065 0.3048)
			(stroke
				(width 0.1)
				(type default)
			)
			(layer "F.Fab")
		)
		(fp_line
			(start -0.12065 -0.2794)
			(end 0.12065 -0.2794)
			(stroke
				(width 0.1)
				(type default)
			)
			(layer "F.Fab")
		)
		(fp_line
			(start -0.12065 -0.305054)
			(end -0.12065 -0.2794)
			(stroke
				(width 0.1)
				(type default)
			)
			(layer "F.Fab")
		)
		(fp_line
			(start -0.67945 0.3048)
			(end -0.67945 -0.305054)
			(stroke
				(width 0.1)
				(type default)
			)
			(layer "F.Fab")
		)
		(fp_line
			(start -0.67945 -0.305054)
			(end -0.12065 -0.305054)
			(stroke
				(width 0.1)
				(type default)
			)
			(layer "F.Fab")
		)
		(pad "1" smd circle
			(at -0.40005 0 180)
			(size 0 0)
			(layers "F.Cu" "F.Mask" "F.Paste")
			(net "M2_0_P3V3_ADC_ALERT_R")
		)
		(pad "2" smd circle
			(at 0.40005 0 180)
			(size 0 0)
			(layers "F.Cu" "F.Mask" "F.Paste")
			(net "M2_0_P3V3_ADC_ALERT")
		)
	)
	(footprint ""
		(layer "F.Cu")
		(at 140.769594 -408.517344 -90)
		(property "Reference" "C1529"
			(at 0 0 270)
			(layer "F.SilkS")
			(hide yes)
			(effects
				(font
					(size 1.27 1.27)
				)
			)
		)
		(property "Value" ""
			(at 0 0 270)
			(layer "F.Fab")
			(effects
				(font
					(size 1.27 1.27)
				)
			)
		)
		(duplicate_pad_numbers_are_jumpers no)
		(fp_line
			(start -0.299974 0.150114)
			(end -0.299974 -0.150114)
			(stroke
				(width 0.1)
				(type default)
			)
			(layer "F.Fab")
		)
		(fp_line
			(start 0.299974 0.150114)
			(end -0.299974 0.150114)
			(stroke
				(width 0.1)
				(type default)
			)
			(layer "F.Fab")
		)
		(fp_line
			(start -0.299974 -0.150114)
			(end 0.299974 -0.150114)
			(stroke
				(width 0.1)
				(type default)
			)
			(layer "F.Fab")
		)
		(fp_line
			(start 0.299974 -0.150114)
			(end 0.299974 0.150114)
			(stroke
				(width 0.1)
				(type default)
			)
			(layer "F.Fab")
		)
		(pad "1" smd rect
			(at -0.2667 0 270)
			(size 0.3048 0.381)
			(layers "F.Cu" "F.Mask" "F.Paste")
			(net "P5E_CPU1_PE3_TX_C_DP<9>")
		)
		(pad "2" smd rect
			(at 0.2667 0 270)
			(size 0.3048 0.381)
			(layers "F.Cu" "F.Mask" "F.Paste")
			(net "P5E_CPU1_PE3_TX_DP<9>")
		)
	)
	(footprint ""
		(layer "F.Cu")
		(at 317.396622 -56.759348 180)
		(property "Reference" "R612"
			(at 0 0 180)
			(layer "F.SilkS")
			(hide yes)
			(effects
				(font
					(size 1.27 1.27)
				)
			)
		)
		(property "Value" ""
			(at 0 0 180)
			(layer "F.Fab")
			(effects
				(font
					(size 1.27 1.27)
				)
			)
		)
		(duplicate_pad_numbers_are_jumpers no)
		(fp_line
			(start 0.7874 0.4064)
			(end -0.7874 0.4064)
			(stroke
				(width 0.1524)
				(type default)
			)
			(layer "F.SilkS")
		)
		(fp_line
			(start 0.7874 -0.4064)
			(end 0.7874 0.4064)
			(stroke
				(width 0.1524)
				(type default)
			)
			(layer "F.SilkS")
		)
		(fp_line
			(start -0.7874 0.4064)
			(end -0.7874 -0.4064)
			(stroke
				(width 0.1524)
				(type default)
			)
			(layer "F.SilkS")
		)
		(fp_line
			(start -0.7874 -0.4064)
			(end 0.7874 -0.4064)
			(stroke
				(width 0.1524)
				(type default)
			)
			(layer "F.SilkS")
		)
		(fp_line
			(start 0.67945 0.3048)
			(end 0.120396 0.3048)
			(stroke
				(width 0.1)
				(type default)
			)
			(layer "F.Fab")
		)
		(fp_line
			(start 0.67945 -0.3048)
			(end 0.67945 0.3048)
			(stroke
				(width 0.1)
				(type default)
			)
			(layer "F.Fab")
		)
		(fp_line
			(start 0.12065 -0.2794)
			(end 0.12065 -0.3048)
			(stroke
				(width 0.1)
				(type default)
			)
			(layer "F.Fab")
		)
		(fp_line
			(start 0.12065 -0.3048)
			(end 0.67945 -0.3048)
			(stroke
				(width 0.1)
				(type default)
			)
			(layer "F.Fab")
		)
		(fp_line
			(start 0.120396 0.3048)
			(end 0.120396 0.2794)
			(stroke
				(width 0.1)
				(type default)
			)
			(layer "F.Fab")
		)
		(fp_line
			(start 0.120396 0.2794)
			(end -0.12065 0.2794)
			(stroke
				(width 0.1)
				(type default)
			)
			(layer "F.Fab")
		)
		(fp_line
			(start -0.12065 0.3048)
			(end -0.67945 0.3048)
			(stroke
				(width 0.1)
				(type default)
			)
			(layer "F.Fab")
		)
		(fp_line
			(start -0.12065 0.2794)
			(end -0.12065 0.3048)
			(stroke
				(width 0.1)
				(type default)
			)
			(layer "F.Fab")
		)
		(fp_line
			(start -0.12065 -0.2794)
			(end 0.12065 -0.2794)
			(stroke
				(width 0.1)
				(type default)
			)
			(layer "F.Fab")
		)
		(fp_line
			(start -0.12065 -0.305054)
			(end -0.12065 -0.2794)
			(stroke
				(width 0.1)
				(type default)
			)
			(layer "F.Fab")
		)
		(fp_line
			(start -0.67945 0.3048)
			(end -0.67945 -0.305054)
			(stroke
				(width 0.1)
				(type default)
			)
			(layer "F.Fab")
		)
		(fp_line
			(start -0.67945 -0.305054)
			(end -0.12065 -0.305054)
			(stroke
				(width 0.1)
				(type default)
			)
			(layer "F.Fab")
		)
		(pad "1" smd circle
			(at -0.40005 0 180)
			(size 0 0)
			(layers "F.Cu" "F.Mask" "F.Paste")
			(net "FM_PCH_EXTERNALCLKMODE")
		)
		(pad "2" smd circle
			(at 0.40005 0 180)
			(size 0 0)
			(layers "F.Cu" "F.Mask" "F.Paste")
			(net "GND")
		)
	)
	(footprint ""
		(layer "F.Cu")
		(at 52.894738 -337.477608)
		(property "Reference" "PC416"
			(at 0 0 0)
			(layer "F.SilkS")
			(hide yes)
			(effects
				(font
					(size 1.27 1.27)
				)
			)
		)
		(property "Value" ""
			(at 0 0 0)
			(layer "F.Fab")
			(effects
				(font
					(size 1.27 1.27)
				)
			)
		)
		(duplicate_pad_numbers_are_jumpers no)
		(fp_line
			(start 2.750058 0.999998)
			(end -2.750058 0.999998)
			(stroke
				(width 0.1524)
				(type default)
			)
			(layer "F.SilkS")
		)
		(fp_circle
			(center 0 0.999998)
			(end 2.750058 0.999998)
			(stroke
				(width 0.1524)
				(type default)
			)
			(fill no)
			(layer "F.SilkS")
		)
		(fp_poly
			(pts
				(arc
					(start 2.750058 0.999998)
					(mid 0 3.750056)
					(end -2.750058 0.999998)
				)
			)
			(stroke
				(width 0)
				(type default)
			)
			(fill yes)
			(layer "F.SilkS")
		)
		(fp_circle
			(center 0 0.999998)
			(end 2.750058 0.999998)
			(stroke
				(width 0.1)
				(type default)
			)
			(fill no)
			(layer "F.Fab")
		)
		(pad "1" thru_hole rect
			(at 0 0)
			(size 1.5748 1.5748)
			(drill 1.0668)
			(layers "*.Cu" "*.Mask")
			(remove_unused_layers no)
			(net "PVCCFA_EHV_FIVRA_CPU1")
			(clearance 0)
			(padstack
				(mode front_inner_back)
				(layer "Inner"
					(shape circle)
					(size 1.5748 1.5748)
					(clearance 0)
				)
				(layer "B.Cu"
					(shape rect)
					(size 1.5748 1.5748)
					(clearance 0)
				)
			)
		)
		(pad "2" thru_hole circle
			(at 0 1.999996)
			(size 1.5748 1.5748)
			(drill 1.0668)
			(layers "*.Cu" "*.Mask")
			(remove_unused_layers no)
			(net "GND")
			(clearance 0)
		)
	)
)
